(kicad_pcb
	(version 20260206)
	(generator "pcbnew")
	(generator_version "10.0")
	(general
		(thickness 1.6)
		(legacy_teardrops no)
	)
	(paper "A4")
	(title_block
		(title "12092022_DA0F0TMDCD0_F0T_Management_Board_D_brd_V3_OCP.brd")
		(comment 1 "Grand Teton / footprints 1105-1110 of 1440")
	)
	(layers
		(0 "F.Cu" signal "TOP")
		(4 "In1.Cu" signal "GND")
		(6 "In2.Cu" signal "IN1")
		(8 "In3.Cu" signal "GND1")
		(10 "In4.Cu" signal "IN2")
		(12 "In5.Cu" signal "VCC")
		(14 "In6.Cu" signal "VCC1")
		(16 "In7.Cu" signal "IN3")
		(18 "In8.Cu" signal "GND2")
		(20 "In9.Cu" signal "IN4")
		(22 "In10.Cu" signal "GND3")
		(2 "B.Cu" signal "BOTTOM")
		(9 "F.Adhes" user "F.Adhesive")
		(11 "B.Adhes" user "B.Adhesive")
		(13 "F.Paste" user "Package Geometry/Pastemask Top")
		(15 "B.Paste" user "Package Geometry/Pastemask Bottom")
		(5 "F.SilkS" user "Ref Des/Silkscreen Top")
		(7 "B.SilkS" user "Ref Des/Silkscreen Bottom")
		(1 "F.Mask" user "Board Geometry/Soldermask Top")
		(3 "B.Mask" user "Board Geometry/Soldermask Bottom")
		(17 "Dwgs.User" user "User.Drawings")
		(19 "Cmts.User" user "User.Comments")
		(21 "Eco1.User" user "User.Eco1")
		(23 "Eco2.User" user "User.Eco2")
		(25 "Edge.Cuts" user "Board Geometry/Outline")
		(27 "Margin" user)
		(31 "F.CrtYd" user "Package Geometry/Place Bound Top")
		(29 "B.CrtYd" user "Package Geometry/Place Bound Bottom")
		(35 "F.Fab" user "Ref Des/Assembly Top")
		(33 "B.Fab" user "Ref Des/Assembly Bottom")
	)
	(footprint ""
		(layer "B.Cu")
		(at 84.08924 -52.397152 180)
		(property "Reference" "C168"
			(at 0 0 0)
			(layer "B.SilkS")
			(hide yes)
			(effects
				(font
					(size 1.27 1.27)
				)
				(justify mirror)
			)
		)
		(property "Value" ""
			(at 0 0 0)
			(layer "B.Fab")
			(effects
				(font
					(size 1.27 1.27)
				)
				(justify mirror)
			)
		)
		(duplicate_pad_numbers_are_jumpers no)
		(fp_line
			(start 0.7874 0.4064)
			(end 0.7874 -0.4064)
			(stroke
				(width 0.1524)
				(type default)
			)
			(layer "B.SilkS")
		)
		(fp_line
			(start 0.7874 -0.4064)
			(end -0.7874 -0.4064)
			(stroke
				(width 0.1524)
				(type default)
			)
			(layer "B.SilkS")
		)
		(fp_line
			(start -0.7874 0.4064)
			(end 0.7874 0.4064)
			(stroke
				(width 0.1524)
				(type default)
			)
			(layer "B.SilkS")
		)
		(fp_line
			(start -0.7874 -0.4064)
			(end -0.7874 0.4064)
			(stroke
				(width 0.1524)
				(type default)
			)
			(layer "B.SilkS")
		)
		(fp_line
			(start 0.67945 0.3048)
			(end 0.67945 -0.305054)
			(stroke
				(width 0.1)
				(type default)
			)
			(layer "B.Fab")
		)
		(fp_line
			(start 0.67945 -0.305054)
			(end 0.12065 -0.305054)
			(stroke
				(width 0.1)
				(type default)
			)
			(layer "B.Fab")
		)
		(fp_line
			(start 0.12065 0.3048)
			(end 0.67945 0.3048)
			(stroke
				(width 0.1)
				(type default)
			)
			(layer "B.Fab")
		)
		(fp_line
			(start 0.12065 0.2794)
			(end 0.12065 0.3048)
			(stroke
				(width 0.1)
				(type default)
			)
			(layer "B.Fab")
		)
		(fp_line
			(start 0.12065 -0.2794)
			(end -0.12065 -0.2794)
			(stroke
				(width 0.1)
				(type default)
			)
			(layer "B.Fab")
		)
		(fp_line
			(start 0.12065 -0.305054)
			(end 0.12065 -0.2794)
			(stroke
				(width 0.1)
				(type default)
			)
			(layer "B.Fab")
		)
		(fp_line
			(start -0.120396 0.3048)
			(end -0.120396 0.2794)
			(stroke
				(width 0.1)
				(type default)
			)
			(layer "B.Fab")
		)
		(fp_line
			(start -0.120396 0.2794)
			(end 0.12065 0.2794)
			(stroke
				(width 0.1)
				(type default)
			)
			(layer "B.Fab")
		)
		(fp_line
			(start -0.12065 -0.2794)
			(end -0.12065 -0.3048)
			(stroke
				(width 0.1)
				(type default)
			)
			(layer "B.Fab")
		)
		(fp_line
			(start -0.12065 -0.3048)
			(end -0.67945 -0.3048)
			(stroke
				(width 0.1)
				(type default)
			)
			(layer "B.Fab")
		)
		(fp_line
			(start -0.67945 0.3048)
			(end -0.120396 0.3048)
			(stroke
				(width 0.1)
				(type default)
			)
			(layer "B.Fab")
		)
		(fp_line
			(start -0.67945 -0.3048)
			(end -0.67945 0.3048)
			(stroke
				(width 0.1)
				(type default)
			)
			(layer "B.Fab")
		)
		(pad "1" smd circle
			(at 0.40005 0)
			(size 0 0)
			(layers "B.Cu" "B.Mask" "B.Paste")
			(net "P0V6_DDR_VREF_AUX")
		)
		(pad "2" smd circle
			(at -0.40005 0)
			(size 0 0)
			(layers "B.Cu" "B.Mask" "B.Paste")
			(net "GND")
		)
	)
	(footprint ""
		(layer "B.Cu")
		(at 63.9572 -89.2048 180)
		(property "Reference" "R745"
			(at 0 0 0)
			(layer "B.SilkS")
			(hide yes)
			(effects
				(font
					(size 1.27 1.27)
				)
				(justify mirror)
			)
		)
		(property "Value" ""
			(at 0 0 0)
			(layer "B.Fab")
			(effects
				(font
					(size 1.27 1.27)
				)
				(justify mirror)
			)
		)
		(duplicate_pad_numbers_are_jumpers no)
		(fp_line
			(start 0.7874 0.4064)
			(end 0.7874 -0.4064)
			(stroke
				(width 0.1524)
				(type default)
			)
			(layer "B.SilkS")
		)
		(fp_line
			(start 0.7874 -0.4064)
			(end -0.7874 -0.4064)
			(stroke
				(width 0.1524)
				(type default)
			)
			(layer "B.SilkS")
		)
		(fp_line
			(start -0.7874 0.4064)
			(end 0.7874 0.4064)
			(stroke
				(width 0.1524)
				(type default)
			)
			(layer "B.SilkS")
		)
		(fp_line
			(start -0.7874 -0.4064)
			(end -0.7874 0.4064)
			(stroke
				(width 0.1524)
				(type default)
			)
			(layer "B.SilkS")
		)
		(fp_line
			(start 0.67945 0.3048)
			(end 0.67945 -0.305054)
			(stroke
				(width 0.1)
				(type default)
			)
			(layer "B.Fab")
		)
		(fp_line
			(start 0.67945 -0.305054)
			(end 0.12065 -0.305054)
			(stroke
				(width 0.1)
				(type default)
			)
			(layer "B.Fab")
		)
		(fp_line
			(start 0.12065 0.3048)
			(end 0.67945 0.3048)
			(stroke
				(width 0.1)
				(type default)
			)
			(layer "B.Fab")
		)
		(fp_line
			(start 0.12065 0.2794)
			(end 0.12065 0.3048)
			(stroke
				(width 0.1)
				(type default)
			)
			(layer "B.Fab")
		)
		(fp_line
			(start 0.12065 -0.2794)
			(end -0.12065 -0.2794)
			(stroke
				(width 0.1)
				(type default)
			)
			(layer "B.Fab")
		)
		(fp_line
			(start 0.12065 -0.305054)
			(end 0.12065 -0.2794)
			(stroke
				(width 0.1)
				(type default)
			)
			(layer "B.Fab")
		)
		(fp_line
			(start -0.120396 0.3048)
			(end -0.120396 0.2794)
			(stroke
				(width 0.1)
				(type default)
			)
			(layer "B.Fab")
		)
		(fp_line
			(start -0.120396 0.2794)
			(end 0.12065 0.2794)
			(stroke
				(width 0.1)
				(type default)
			)
			(layer "B.Fab")
		)
		(fp_line
			(start -0.12065 -0.2794)
			(end -0.12065 -0.3048)
			(stroke
				(width 0.1)
				(type default)
			)
			(layer "B.Fab")
		)
		(fp_line
			(start -0.12065 -0.3048)
			(end -0.67945 -0.3048)
			(stroke
				(width 0.1)
				(type default)
			)
			(layer "B.Fab")
		)
		(fp_line
			(start -0.67945 0.3048)
			(end -0.120396 0.3048)
			(stroke
				(width 0.1)
				(type default)
			)
			(layer "B.Fab")
		)
		(fp_line
			(start -0.67945 -0.3048)
			(end -0.67945 0.3048)
			(stroke
				(width 0.1)
				(type default)
			)
			(layer "B.Fab")
		)
		(pad "1" smd circle
			(at 0.40005 0)
			(size 0 0)
			(layers "B.Cu" "B.Mask" "B.Paste")
			(net "LED_POSTCODE_A2")
		)
		(pad "2" smd circle
			(at -0.40005 0)
			(size 0 0)
			(layers "B.Cu" "B.Mask" "B.Paste")
			(net "GND")
		)
	)
	(footprint ""
		(layer "B.Cu")
		(at 17.907 -101.981 -90)
		(property "Reference" "R379"
			(at 0 0 90)
			(layer "B.SilkS")
			(hide yes)
			(effects
				(font
					(size 1.27 1.27)
				)
				(justify mirror)
			)
		)
		(property "Value" ""
			(at 0 0 90)
			(layer "B.Fab")
			(effects
				(font
					(size 1.27 1.27)
				)
				(justify mirror)
			)
		)
		(duplicate_pad_numbers_are_jumpers no)
		(fp_line
			(start -0.7874 0.4064)
			(end 0.7874 0.4064)
			(stroke
				(width 0.1524)
				(type default)
			)
			(layer "B.SilkS")
		)
		(fp_line
			(start 0.7874 0.4064)
			(end 0.7874 -0.4064)
			(stroke
				(width 0.1524)
				(type default)
			)
			(layer "B.SilkS")
		)
		(fp_line
			(start -0.7874 -0.4064)
			(end -0.7874 0.4064)
			(stroke
				(width 0.1524)
				(type default)
			)
			(layer "B.SilkS")
		)
		(fp_line
			(start 0.7874 -0.4064)
			(end -0.7874 -0.4064)
			(stroke
				(width 0.1524)
				(type default)
			)
			(layer "B.SilkS")
		)
		(fp_line
			(start -0.67945 0.3048)
			(end -0.120396 0.3048)
			(stroke
				(width 0.1)
				(type default)
			)
			(layer "B.Fab")
		)
		(fp_line
			(start -0.120396 0.3048)
			(end -0.120396 0.2794)
			(stroke
				(width 0.1)
				(type default)
			)
			(layer "B.Fab")
		)
		(fp_line
			(start 0.12065 0.3048)
			(end 0.67945 0.3048)
			(stroke
				(width 0.1)
				(type default)
			)
			(layer "B.Fab")
		)
		(fp_line
			(start 0.67945 0.3048)
			(end 0.67945 -0.305054)
			(stroke
				(width 0.1)
				(type default)
			)
			(layer "B.Fab")
		)
		(fp_line
			(start -0.120396 0.2794)
			(end 0.12065 0.2794)
			(stroke
				(width 0.1)
				(type default)
			)
			(layer "B.Fab")
		)
		(fp_line
			(start 0.12065 0.2794)
			(end 0.12065 0.3048)
			(stroke
				(width 0.1)
				(type default)
			)
			(layer "B.Fab")
		)
		(fp_line
			(start -0.12065 -0.2794)
			(end -0.12065 -0.3048)
			(stroke
				(width 0.1)
				(type default)
			)
			(layer "B.Fab")
		)
		(fp_line
			(start 0.12065 -0.2794)
			(end -0.12065 -0.2794)
			(stroke
				(width 0.1)
				(type default)
			)
			(layer "B.Fab")
		)
		(fp_line
			(start -0.67945 -0.3048)
			(end -0.67945 0.3048)
			(stroke
				(width 0.1)
				(type default)
			)
			(layer "B.Fab")
		)
		(fp_line
			(start -0.12065 -0.3048)
			(end -0.67945 -0.3048)
			(stroke
				(width 0.1)
				(type default)
			)
			(layer "B.Fab")
		)
		(fp_line
			(start 0.12065 -0.305054)
			(end 0.12065 -0.2794)
			(stroke
				(width 0.1)
				(type default)
			)
			(layer "B.Fab")
		)
		(fp_line
			(start 0.67945 -0.305054)
			(end 0.12065 -0.305054)
			(stroke
				(width 0.1)
				(type default)
			)
			(layer "B.Fab")
		)
		(pad "1" smd circle
			(at 0.40005 0 90)
			(size 0 0)
			(layers "B.Cu" "B.Mask" "B.Paste")
			(net "PWRGD_P1V0_AUX_R1")
		)
		(pad "2" smd circle
			(at -0.40005 0 90)
			(size 0 0)
			(layers "B.Cu" "B.Mask" "B.Paste")
			(net "PWRGD_P1V0_AUX")
		)
	)
	(footprint ""
		(layer "B.Cu")
		(at 42.220134 -39.95166)
		(property "Reference" "R171"
			(at 0 0 0)
			(layer "B.SilkS")
			(hide yes)
			(effects
				(font
					(size 1.27 1.27)
				)
				(justify mirror)
			)
		)
		(property "Value" ""
			(at 0 0 0)
			(layer "B.Fab")
			(effects
				(font
					(size 1.27 1.27)
				)
				(justify mirror)
			)
		)
		(duplicate_pad_numbers_are_jumpers no)
		(fp_line
			(start -0.7874 -0.4064)
			(end -0.7874 0.4064)
			(stroke
				(width 0.1524)
				(type default)
			)
			(layer "B.SilkS")
		)
		(fp_line
			(start -0.7874 0.4064)
			(end 0.7874 0.4064)
			(stroke
				(width 0.1524)
				(type default)
			)
			(layer "B.SilkS")
		)
		(fp_line
			(start 0.7874 -0.4064)
			(end -0.7874 -0.4064)
			(stroke
				(width 0.1524)
				(type default)
			)
			(layer "B.SilkS")
		)
		(fp_line
			(start 0.7874 0.4064)
			(end 0.7874 -0.4064)
			(stroke
				(width 0.1524)
				(type default)
			)
			(layer "B.SilkS")
		)
		(fp_line
			(start -0.67945 -0.3048)
			(end -0.67945 0.3048)
			(stroke
				(width 0.1)
				(type default)
			)
			(layer "B.Fab")
		)
		(fp_line
			(start -0.67945 0.3048)
			(end -0.120396 0.3048)
			(stroke
				(width 0.1)
				(type default)
			)
			(layer "B.Fab")
		)
		(fp_line
			(start -0.12065 -0.3048)
			(end -0.67945 -0.3048)
			(stroke
				(width 0.1)
				(type default)
			)
			(layer "B.Fab")
		)
		(fp_line
			(start -0.12065 -0.2794)
			(end -0.12065 -0.3048)
			(stroke
				(width 0.1)
				(type default)
			)
			(layer "B.Fab")
		)
		(fp_line
			(start -0.120396 0.2794)
			(end 0.12065 0.2794)
			(stroke
				(width 0.1)
				(type default)
			)
			(layer "B.Fab")
		)
		(fp_line
			(start -0.120396 0.3048)
			(end -0.120396 0.2794)
			(stroke
				(width 0.1)
				(type default)
			)
			(layer "B.Fab")
		)
		(fp_line
			(start 0.12065 -0.305054)
			(end 0.12065 -0.2794)
			(stroke
				(width 0.1)
				(type default)
			)
			(layer "B.Fab")
		)
		(fp_line
			(start 0.12065 -0.2794)
			(end -0.12065 -0.2794)
			(stroke
				(width 0.1)
				(type default)
			)
			(layer "B.Fab")
		)
		(fp_line
			(start 0.12065 0.2794)
			(end 0.12065 0.3048)
			(stroke
				(width 0.1)
				(type default)
			)
			(layer "B.Fab")
		)
		(fp_line
			(start 0.12065 0.3048)
			(end 0.67945 0.3048)
			(stroke
				(width 0.1)
				(type default)
			)
			(layer "B.Fab")
		)
		(fp_line
			(start 0.67945 -0.305054)
			(end 0.12065 -0.305054)
			(stroke
				(width 0.1)
				(type default)
			)
			(layer "B.Fab")
		)
		(fp_line
			(start 0.67945 0.3048)
			(end 0.67945 -0.305054)
			(stroke
				(width 0.1)
				(type default)
			)
			(layer "B.Fab")
		)
		(pad "1" smd circle
			(at 0.40005 0 180)
			(size 0 0)
			(layers "B.Cu" "B.Mask" "B.Paste")
			(net "RMII_TXEN_R")
		)
		(pad "2" smd circle
			(at -0.40005 0 180)
			(size 0 0)
			(layers "B.Cu" "B.Mask" "B.Paste")
			(net "RMII_TXEN")
		)
	)
	(footprint ""
		(layer "B.Cu")
		(at 51.30546 -51.69154 180)
		(property "Reference" "C112"
			(at 0 0 0)
			(layer "B.SilkS")
			(hide yes)
			(effects
				(font
					(size 1.27 1.27)
				)
				(justify mirror)
			)
		)
		(property "Value" ""
			(at 0 0 0)
			(layer "B.Fab")
			(effects
				(font
					(size 1.27 1.27)
				)
				(justify mirror)
			)
		)
		(duplicate_pad_numbers_are_jumpers no)
		(fp_line
			(start 0.7874 0.4064)
			(end 0.7874 -0.4064)
			(stroke
				(width 0.1524)
				(type default)
			)
			(layer "B.SilkS")
		)
		(fp_line
			(start 0.7874 -0.4064)
			(end -0.7874 -0.4064)
			(stroke
				(width 0.1524)
				(type default)
			)
			(layer "B.SilkS")
		)
		(fp_line
			(start -0.7874 0.4064)
			(end 0.7874 0.4064)
			(stroke
				(width 0.1524)
				(type default)
			)
			(layer "B.SilkS")
		)
		(fp_line
			(start -0.7874 -0.4064)
			(end -0.7874 0.4064)
			(stroke
				(width 0.1524)
				(type default)
			)
			(layer "B.SilkS")
		)
		(fp_line
			(start 0.67945 0.3048)
			(end 0.67945 -0.305054)
			(stroke
				(width 0.1)
				(type default)
			)
			(layer "B.Fab")
		)
		(fp_line
			(start 0.67945 -0.305054)
			(end 0.12065 -0.305054)
			(stroke
				(width 0.1)
				(type default)
			)
			(layer "B.Fab")
		)
		(fp_line
			(start 0.12065 0.3048)
			(end 0.67945 0.3048)
			(stroke
				(width 0.1)
				(type default)
			)
			(layer "B.Fab")
		)
		(fp_line
			(start 0.12065 0.2794)
			(end 0.12065 0.3048)
			(stroke
				(width 0.1)
				(type default)
			)
			(layer "B.Fab")
		)
		(fp_line
			(start 0.12065 -0.2794)
			(end -0.12065 -0.2794)
			(stroke
				(width 0.1)
				(type default)
			)
			(layer "B.Fab")
		)
		(fp_line
			(start 0.12065 -0.305054)
			(end 0.12065 -0.2794)
			(stroke
				(width 0.1)
				(type default)
			)
			(layer "B.Fab")
		)
		(fp_line
			(start -0.120396 0.3048)
			(end -0.120396 0.2794)
			(stroke
				(width 0.1)
				(type default)
			)
			(layer "B.Fab")
		)
		(fp_line
			(start -0.120396 0.2794)
			(end 0.12065 0.2794)
			(stroke
				(width 0.1)
				(type default)
			)
			(layer "B.Fab")
		)
		(fp_line
			(start -0.12065 -0.2794)
			(end -0.12065 -0.3048)
			(stroke
				(width 0.1)
				(type default)
			)
			(layer "B.Fab")
		)
		(fp_line
			(start -0.12065 -0.3048)
			(end -0.67945 -0.3048)
			(stroke
				(width 0.1)
				(type default)
			)
			(layer "B.Fab")
		)
		(fp_line
			(start -0.67945 0.3048)
			(end -0.120396 0.3048)
			(stroke
				(width 0.1)
				(type default)
			)
			(layer "B.Fab")
		)
		(fp_line
			(start -0.67945 -0.3048)
			(end -0.67945 0.3048)
			(stroke
				(width 0.1)
				(type default)
			)
			(layer "B.Fab")
		)
		(pad "1" smd circle
			(at 0.40005 0)
			(size 0 0)
			(layers "B.Cu" "B.Mask" "B.Paste")
			(net "P1V2_AUX")
		)
		(pad "2" smd circle
			(at -0.40005 0)
			(size 0 0)
			(layers "B.Cu" "B.Mask" "B.Paste")
			(net "GND")
		)
	)
	(footprint ""
		(layer "B.Cu")
		(at 51.558952 -43.765216)
		(property "Reference" "C101"
			(at 0 0 0)
			(layer "B.SilkS")
			(hide yes)
			(effects
				(font
					(size 1.27 1.27)
				)
				(justify mirror)
			)
		)
		(property "Value" ""
			(at 0 0 0)
			(layer "B.Fab")
			(effects
				(font
					(size 1.27 1.27)
				)
				(justify mirror)
			)
		)
		(duplicate_pad_numbers_are_jumpers no)
		(fp_line
			(start -0.7874 -0.4064)
			(end -0.7874 0.4064)
			(stroke
				(width 0.1524)
				(type default)
			)
			(layer "B.SilkS")
		)
		(fp_line
			(start -0.7874 0.4064)
			(end 0.7874 0.4064)
			(stroke
				(width 0.1524)
				(type default)
			)
			(layer "B.SilkS")
		)
		(fp_line
			(start 0.7874 -0.4064)
			(end -0.7874 -0.4064)
			(stroke
				(width 0.1524)
				(type default)
			)
			(layer "B.SilkS")
		)
		(fp_line
			(start 0.7874 0.4064)
			(end 0.7874 -0.4064)
			(stroke
				(width 0.1524)
				(type default)
			)
			(layer "B.SilkS")
		)
		(fp_line
			(start -0.67945 -0.3048)
			(end -0.67945 0.3048)
			(stroke
				(width 0.1)
				(type default)
			)
			(layer "B.Fab")
		)
		(fp_line
			(start -0.67945 0.3048)
			(end -0.120396 0.3048)
			(stroke
				(width 0.1)
				(type default)
			)
			(layer "B.Fab")
		)
		(fp_line
			(start -0.12065 -0.3048)
			(end -0.67945 -0.3048)
			(stroke
				(width 0.1)
				(type default)
			)
			(layer "B.Fab")
		)
		(fp_line
			(start -0.12065 -0.2794)
			(end -0.12065 -0.3048)
			(stroke
				(width 0.1)
				(type default)
			)
			(layer "B.Fab")
		)
		(fp_line
			(start -0.120396 0.2794)
			(end 0.12065 0.2794)
			(stroke
				(width 0.1)
				(type default)
			)
			(layer "B.Fab")
		)
		(fp_line
			(start -0.120396 0.3048)
			(end -0.120396 0.2794)
			(stroke
				(width 0.1)
				(type default)
			)
			(layer "B.Fab")
		)
		(fp_line
			(start 0.12065 -0.305054)
			(end 0.12065 -0.2794)
			(stroke
				(width 0.1)
				(type default)
			)
			(layer "B.Fab")
		)
		(fp_line
			(start 0.12065 -0.2794)
			(end -0.12065 -0.2794)
			(stroke
				(width 0.1)
				(type default)
			)
			(layer "B.Fab")
		)
		(fp_line
			(start 0.12065 0.2794)
			(end 0.12065 0.3048)
			(stroke
				(width 0.1)
				(type default)
			)
			(layer "B.Fab")
		)
		(fp_line
			(start 0.12065 0.3048)
			(end 0.67945 0.3048)
			(stroke
				(width 0.1)
				(type default)
			)
			(layer "B.Fab")
		)
		(fp_line
			(start 0.67945 -0.305054)
			(end 0.12065 -0.305054)
			(stroke
				(width 0.1)
				(type default)
			)
			(layer "B.Fab")
		)
		(fp_line
			(start 0.67945 0.3048)
			(end 0.67945 -0.305054)
			(stroke
				(width 0.1)
				(type default)
			)
			(layer "B.Fab")
		)
		(pad "1" smd circle
			(at 0.40005 0 180)
			(size 0 0)
			(layers "B.Cu" "B.Mask" "B.Paste")
			(net "P3V3_AUX")
		)
		(pad "2" smd circle
			(at -0.40005 0 180)
			(size 0 0)
			(layers "B.Cu" "B.Mask" "B.Paste")
			(net "GND")
		)
	)
)
